(kicad_pcb
	(version 20260206)
	(generator "pcbnew")
	(generator_version "10.0")
	(general
		(thickness 1.6)
		(legacy_teardrops no)
	)
	(paper "A4")
	(title_block
		(title "m-2 — Lightning_M.2_BRD.brd")
		(comment 1 "Lightning (Wiwynn / Facebook NVMe JBOF) / footprints 54-59 of 157")
	)
	(layers
		(0 "F.Cu" signal "TOP")
		(4 "In1.Cu" signal "L2GND")
		(6 "In2.Cu" signal "L3")
		(8 "In3.Cu" signal "L4GND")
		(10 "In4.Cu" signal "L5GND")
		(12 "In5.Cu" signal "L6")
		(14 "In6.Cu" signal "L7GND")
		(2 "B.Cu" signal "BOTTOM")
		(9 "F.Adhes" user "F.Adhesive")
		(11 "B.Adhes" user "B.Adhesive")
		(13 "F.Paste" user "Package Geometry/Pastemask Top")
		(15 "B.Paste" user "Package Geometry/Pastemask Bottom")
		(5 "F.SilkS" user "Ref Des/Silkscreen Top")
		(7 "B.SilkS" user "Ref Des/Silkscreen Bottom")
		(1 "F.Mask" user "Board Geometry/Soldermask Top")
		(3 "B.Mask" user "Board Geometry/Soldermask Bottom")
		(17 "Dwgs.User" user "User.Drawings")
		(19 "Cmts.User" user "User.Comments")
		(21 "Eco1.User" user "User.Eco1")
		(23 "Eco2.User" user "User.Eco2")
		(25 "Edge.Cuts" user "Board Geometry/Outline")
		(27 "Margin" user)
		(31 "F.CrtYd" user "Package Geometry/Place Bound Top")
		(29 "B.CrtYd" user "Package Geometry/Place Bound Bottom")
		(35 "F.Fab" user "Ref Des/Assembly Top")
		(33 "B.Fab" user "Ref Des/Assembly Bottom")
	)
	(footprint ""
		(layer "F.Cu")
		(at 17.526 -75.867006 -90)
		(property "Reference" "PR22"
			(at 0 0 270)
			(layer "F.SilkS")
			(hide yes)
			(effects
				(font
					(size 1.27 1.27)
				)
			)
		)
		(property "Value" "3K65R2F-1-GP"
			(at 0.064008 -3.993896 270)
			(unlocked yes)
			(layer "F.Fab")
			(hide yes)
			(effects
				(font
					(size 1.016 1.016)
					(thickness 0.1524)
				)
			)
		)
		(property "Device Type" "R402H16"
			(at 0.064008 -5.517896 270)
			(unlocked yes)
			(layer "F.Fab")
			(hide yes)
			(effects
				(font
					(size 1.016 1.016)
					(thickness 0.1524)
				)
			)
		)
		(duplicate_pad_numbers_are_jumpers no)
		(fp_line
			(start -0.508 -0.9398)
			(end -0.508 0.9398)
			(stroke
				(width 0.1524)
				(type default)
			)
			(layer "F.SilkS")
		)
		(fp_line
			(start 0.508 -0.9398)
			(end -0.508 -0.9398)
			(stroke
				(width 0.1524)
				(type default)
			)
			(layer "F.SilkS")
		)
		(fp_rect
			(start -0.508 0.9398)
			(end 0.508 -0.9398)
			(stroke
				(width 0)
				(type default)
			)
			(fill no)
			(layer "F.CrtYd")
		)
		(fp_rect
			(start -0.508 0.9398)
			(end 0.508 -0.9398)
			(stroke
				(width 0)
				(type default)
			)
			(fill no)
			(layer "F.Fab")
		)
		(pad "1" smd custom
			(at 0 -0.4445 270)
			(size 0.1397 0.1397)
			(layers "F.Cu" "F.Mask" "F.Paste")
			(net "P1V8_PWR")
			(options
				(clearance outline)
				(anchor circle)
			)
			(primitives
				(gr_poly
					(pts
						(arc
							(start -0.1778 -0.2794)
							(mid -0.249642 -0.249642)
							(end -0.2794 -0.1778)
						)
						(arc
							(start -0.2794 0.1778)
							(mid -0.249642 0.249642)
							(end -0.1778 0.2794)
						)
						(arc
							(start 0.1778 0.2794)
							(mid 0.249642 0.249642)
							(end 0.2794 0.1778)
						)
						(arc
							(start 0.2794 -0.1778)
							(mid 0.249642 -0.249642)
							(end 0.1778 -0.2794)
						)
					)
					(width 0)
					(fill yes)
				)
			)
		)
		(pad "2" smd custom
			(at 0 0.4445 270)
			(size 0.1397 0.1397)
			(layers "F.Cu" "F.Mask" "F.Paste")
			(net "P1V8_PWR_FB")
			(options
				(clearance outline)
				(anchor circle)
			)
			(primitives
				(gr_poly
					(pts
						(arc
							(start -0.1778 -0.2794)
							(mid -0.249642 -0.249642)
							(end -0.2794 -0.1778)
						)
						(arc
							(start -0.2794 0.1778)
							(mid -0.249642 0.249642)
							(end -0.1778 0.2794)
						)
						(arc
							(start 0.1778 0.2794)
							(mid 0.249642 0.249642)
							(end 0.2794 0.1778)
						)
						(arc
							(start 0.2794 -0.1778)
							(mid 0.249642 -0.249642)
							(end 0.1778 -0.2794)
						)
					)
					(width 0)
					(fill yes)
				)
			)
		)
	)
	(footprint ""
		(layer "F.Cu")
		(at 53.1114 -76.2508 -90)
		(property "Reference" "PC43"
			(at 0 0 270)
			(layer "F.SilkS")
			(hide yes)
			(effects
				(font
					(size 1.27 1.27)
				)
			)
		)
		(property "Value" "SC1KP50V2KX-1GP"
			(at 1.1811 -2.7051 270)
			(unlocked yes)
			(layer "F.Fab")
			(hide yes)
			(effects
				(font
					(size 1.016 1.016)
					(thickness 0.1524)
				)
			)
		)
		(property "Device Type" "C402H22"
			(at 1.1811 -4.2291 270)
			(unlocked yes)
			(layer "F.Fab")
			(hide yes)
			(effects
				(font
					(size 1.016 1.016)
					(thickness 0.1524)
				)
			)
		)
		(duplicate_pad_numbers_are_jumpers no)
		(fp_rect
			(start -0.4318 0.9525)
			(end 0.4318 -0.9525)
			(stroke
				(width 0)
				(type default)
			)
			(fill no)
			(layer "F.CrtYd")
		)
		(fp_rect
			(start -0.4318 0.9525)
			(end 0.4318 -0.9525)
			(stroke
				(width 0)
				(type default)
			)
			(fill no)
			(layer "F.Fab")
		)
		(pad "1" smd custom
			(at 0 -0.4445 270)
			(size 0.1524 0.1524)
			(layers "F.Cu" "F.Mask" "F.Paste")
			(net "P3V3_DEV_LL_R")
			(options
				(clearance outline)
				(anchor circle)
			)
			(primitives
				(gr_poly
					(pts
						(arc
							(start 0.3048 -0.2032)
							(mid 0.275042 -0.275042)
							(end 0.2032 -0.3048)
						)
						(arc
							(start -0.2032 -0.3048)
							(mid -0.275042 -0.275042)
							(end -0.3048 -0.2032)
						)
						(arc
							(start -0.3048 0.2032)
							(mid -0.275042 0.275042)
							(end -0.2032 0.3048)
						)
						(arc
							(start 0.2032 0.3048)
							(mid 0.275042 0.275042)
							(end 0.3048 0.2032)
						)
					)
					(width 0)
					(fill yes)
				)
			)
		)
		(pad "2" smd custom
			(at 0 0.4445 270)
			(size 0.1524 0.1524)
			(layers "F.Cu" "F.Mask" "F.Paste")
			(net "P3V3_DEV_VFB")
			(options
				(clearance outline)
				(anchor circle)
			)
			(primitives
				(gr_poly
					(pts
						(arc
							(start 0.3048 -0.2032)
							(mid 0.275042 -0.275042)
							(end 0.2032 -0.3048)
						)
						(arc
							(start -0.2032 -0.3048)
							(mid -0.275042 -0.275042)
							(end -0.3048 -0.2032)
						)
						(arc
							(start -0.3048 0.2032)
							(mid -0.275042 0.275042)
							(end -0.2032 0.3048)
						)
						(arc
							(start 0.2032 0.3048)
							(mid 0.275042 0.275042)
							(end 0.3048 0.2032)
						)
					)
					(width 0)
					(fill yes)
				)
			)
		)
	)
	(footprint ""
		(layer "F.Cu")
		(at 47.195994 -80.899 -90)
		(property "Reference" "PU1"
			(at 0 0 270)
			(layer "F.SilkS")
			(hide yes)
			(effects
				(font
					(size 1.27 1.27)
				)
			)
		)
		(property "Value" "TPS53319DQPR-GP"
			(at 4.7498 -5.6896 270)
			(unlocked yes)
			(layer "F.Fab")
			(hide yes)
			(effects
				(font
					(size 1.016 1.016)
					(thickness 0.1524)
				)
			)
		)
		(property "Device Type" "QFN22G6050-G6133H60"
			(at 4.7498 -7.2136 270)
			(unlocked yes)
			(layer "F.Fab")
			(hide yes)
			(effects
				(font
					(size 1.016 1.016)
					(thickness 0.1524)
				)
			)
		)
		(duplicate_pad_numbers_are_jumpers no)
		(fp_line
			(start -3.556 3.5179)
			(end -2.286 3.5179)
			(stroke
				(width 0.1524)
				(type default)
			)
			(layer "F.SilkS")
		)
		(fp_line
			(start 2.286 3.5179)
			(end 3.556 3.5179)
			(stroke
				(width 0.1524)
				(type default)
			)
			(layer "F.SilkS")
		)
		(fp_line
			(start 3.556 3.5179)
			(end 3.556 2.2479)
			(stroke
				(width 0.1524)
				(type default)
			)
			(layer "F.SilkS")
		)
		(fp_line
			(start -0.999998 3.262122)
			(end -0.999998 3.770122)
			(stroke
				(width 0.1524)
				(type default)
			)
			(layer "F.SilkS")
		)
		(fp_line
			(start 1.500124 3.262122)
			(end 1.500124 4.024122)
			(stroke
				(width 0.1524)
				(type default)
			)
			(layer "F.SilkS")
		)
		(fp_line
			(start -3.556 2.2479)
			(end -3.556 3.5179)
			(stroke
				(width 0.1524)
				(type default)
			)
			(layer "F.SilkS")
		)
		(fp_line
			(start -1.999996 -3.262122)
			(end -1.999996 -4.024122)
			(stroke
				(width 0.1524)
				(type default)
			)
			(layer "F.SilkS")
		)
		(fp_line
			(start 0.500126 -3.262122)
			(end 0.500126 -3.770122)
			(stroke
				(width 0.1524)
				(type default)
			)
			(layer "F.SilkS")
		)
		(fp_line
			(start -3.556 -3.5179)
			(end -3.556 -2.2479)
			(stroke
				(width 0.1524)
				(type default)
			)
			(layer "F.SilkS")
		)
		(fp_line
			(start -2.286 -3.5179)
			(end -3.556 -3.5179)
			(stroke
				(width 0.1524)
				(type default)
			)
			(layer "F.SilkS")
		)
		(fp_poly
			(pts
				(xy 3.556 -3.5179) (xy 2.5273 -3.5179) (xy 3.556 -2.4892)
			)
			(stroke
				(width 0)
				(type default)
			)
			(fill yes)
			(layer "F.SilkS")
		)
		(fp_rect
			(start -2.9972 2.5019)
			(end 2.9972 -2.5019)
			(stroke
				(width 0)
				(type default)
			)
			(fill no)
			(layer "F.CrtYd")
		)
		(fp_poly
			(pts
				(xy 3.556 -2.5019) (xy -2.9972 -2.5019) (xy -2.9972 2.5019) (xy 2.9972 2.5019) (xy 2.9972 -2.4892)
				(xy 3.556 -2.4892) (xy 3.556 3.5179) (xy -3.556 3.5179) (xy -3.556 -3.5179) (xy 3.556 -3.5179)
			)
			(stroke
				(width 0)
				(type default)
			)
			(fill no)
			(layer "F.CrtYd")
		)
		(fp_rect
			(start -3.556 3.5179)
			(end 3.556 -3.5179)
			(stroke
				(width 0)
				(type default)
			)
			(fill no)
			(layer "F.Fab")
		)
		(pad "1" smd rect
			(at 2.500122 -2.449322 270)
			(size 0.3048 1.1176)
			(layers "F.Cu" "F.Mask" "F.Paste")
			(net "P3V3_DEV_VFB")
		)
		(pad "2" smd rect
			(at 1.999996 -2.449322 270)
			(size 0.3048 1.1176)
			(layers "F.Cu" "F.Mask" "F.Paste")
			(net "P3V3_DEV_EN")
		)
		(pad "3" smd rect
			(at 1.500124 -2.449322 270)
			(size 0.3048 1.1176)
			(layers "F.Cu" "F.Mask" "F.Paste")
			(net "P3V3_DEV_PWRGD")
		)
		(pad "4" smd rect
			(at 0.999998 -2.449322 270)
			(size 0.3048 1.1176)
			(layers "F.Cu" "F.Mask" "F.Paste")
			(net "P3V3_DEV_VBST")
		)
		(pad "5" smd rect
			(at 0.500126 -2.449322 270)
			(size 0.3048 1.1176)
			(layers "F.Cu" "F.Mask" "F.Paste")
			(net "P3V3_DEV_ROVP")
		)
		(pad "6" smd rect
			(at 0 -2.449322 270)
			(size 0.3048 1.1176)
			(layers "F.Cu" "F.Mask" "F.Paste")
			(net "P3V3_DEV_LL")
		)
		(pad "7" smd rect
			(at -0.500126 -2.449322 270)
			(size 0.3048 1.1176)
			(layers "F.Cu" "F.Mask" "F.Paste")
			(net "P3V3_DEV_LL")
		)
		(pad "8" smd rect
			(at -0.999998 -2.449322 270)
			(size 0.3048 1.1176)
			(layers "F.Cu" "F.Mask" "F.Paste")
			(net "P3V3_DEV_LL")
		)
		(pad "9" smd rect
			(at -1.500124 -2.449322 270)
			(size 0.3048 1.1176)
			(layers "F.Cu" "F.Mask" "F.Paste")
			(net "P3V3_DEV_LL")
		)
		(pad "10" smd rect
			(at -1.999996 -2.449322 270)
			(size 0.3048 1.1176)
			(layers "F.Cu" "F.Mask" "F.Paste")
			(net "P3V3_DEV_LL")
		)
		(pad "11" smd rect
			(at -2.500122 -2.449322 270)
			(size 0.3048 1.1176)
			(layers "F.Cu" "F.Mask" "F.Paste")
			(net "P3V3_DEV_LL")
		)
		(pad "12" smd rect
			(at -2.500122 2.449322 270)
			(size 0.3048 1.1176)
			(layers "F.Cu" "F.Mask" "F.Paste")
			(net "P3V3_DEV_VIN")
		)
		(pad "13" smd rect
			(at -1.999996 2.449322 270)
			(size 0.3048 1.1176)
			(layers "F.Cu" "F.Mask" "F.Paste")
			(net "P3V3_DEV_VIN")
		)
		(pad "14" smd rect
			(at -1.500124 2.449322 270)
			(size 0.3048 1.1176)
			(layers "F.Cu" "F.Mask" "F.Paste")
			(net "P3V3_DEV_VIN")
		)
		(pad "15" smd rect
			(at -0.999998 2.449322 270)
			(size 0.3048 1.1176)
			(layers "F.Cu" "F.Mask" "F.Paste")
			(net "P3V3_DEV_VIN")
		)
		(pad "16" smd rect
			(at -0.500126 2.449322 270)
			(size 0.3048 1.1176)
			(layers "F.Cu" "F.Mask" "F.Paste")
			(net "P3V3_DEV_VIN")
		)
		(pad "17" smd rect
			(at 0 2.449322 270)
			(size 0.3048 1.1176)
			(layers "F.Cu" "F.Mask" "F.Paste")
			(net "P3V3_DEV_VIN")
		)
		(pad "18" smd rect
			(at 0.500126 2.449322 270)
			(size 0.3048 1.1176)
			(layers "F.Cu" "F.Mask" "F.Paste")
			(net "P3V3_DEV_VREG")
		)
		(pad "19" smd rect
			(at 0.999998 2.449322 270)
			(size 0.3048 1.1176)
			(layers "F.Cu" "F.Mask" "F.Paste")
			(net "P3V3_DEV_VDD")
		)
		(pad "20" smd rect
			(at 1.500124 2.449322 270)
			(size 0.3048 1.1176)
			(layers "F.Cu" "F.Mask" "F.Paste")
			(net "P3V3_DEV_MODE")
		)
		(pad "21" smd rect
			(at 1.999996 2.449322 270)
			(size 0.3048 1.1176)
			(layers "F.Cu" "F.Mask" "F.Paste")
			(net "P3V3_DEV_TRIP")
		)
		(pad "22" smd rect
			(at 2.500122 2.449322 270)
			(size 0.3048 1.1176)
			(layers "F.Cu" "F.Mask" "F.Paste")
			(net "P3V3_DEV_RF")
		)
		(pad "23" smd custom
			(at 0 0 270)
			(size 0.83185 0.83185)
			(layers "F.Cu" "F.Mask" "F.Paste")
			(net "GND")
			(options
				(clearance outline)
				(anchor circle)
			)
			(primitives
				(gr_poly
					(pts
						(xy -2.7813 1.6637) (xy -2.7813 1.2954) (xy -3.048 1.2954) (xy -3.048 0.9525) (xy -2.7813 0.9525)
						(xy -2.7813 -0.9525) (xy -3.048 -0.9525) (xy -3.048 -1.2954) (xy -2.7813 -1.2954) (xy -2.7813 -1.6637)
						(xy 2.7813 -1.6637) (xy 2.7813 -1.2954) (xy 3.048 -1.2954) (xy 3.048 -0.9525) (xy 2.7813 -0.9525)
						(xy 2.7813 0.9525) (xy 3.048 0.9525) (xy 3.048 1.2954) (xy 2.7813 1.2954) (xy 2.7813 1.6637)
					)
					(width 0)
					(fill yes)
				)
			)
		)
	)
	(footprint ""
		(layer "F.Cu")
		(at 20.447 -76.629006 90)
		(property "Reference" "PC25"
			(at 0 0 90)
			(layer "F.SilkS")
			(hide yes)
			(effects
				(font
					(size 1.27 1.27)
				)
			)
		)
		(property "Value" "SC22U6D3V5MX-5-GP"
			(at -0.0762 -6.1214 90)
			(unlocked yes)
			(layer "F.Fab")
			(hide yes)
			(effects
				(font
					(size 1.016 1.016)
					(thickness 0.1524)
				)
			)
		)
		(property "Device Type" "C805H56"
			(at -0.0762 -8.1534 90)
			(unlocked yes)
			(layer "F.Fab")
			(hide yes)
			(effects
				(font
					(size 1.016 1.016)
					(thickness 0.1524)
				)
			)
		)
		(duplicate_pad_numbers_are_jumpers no)
		(fp_line
			(start 0.635 0)
			(end -0.635 0)
			(stroke
				(width 0.508)
				(type default)
			)
			(layer "F.SilkS")
		)
		(fp_rect
			(start -0.9652 1.778)
			(end 0.9652 -1.778)
			(stroke
				(width 0)
				(type default)
			)
			(fill no)
			(layer "F.CrtYd")
		)
		(fp_poly
			(pts
				(xy -0.9652 -1.778) (xy 0.9652 -1.778) (xy 0.9652 1.778) (xy -0.9652 1.778)
			)
			(stroke
				(width 0)
				(type default)
			)
			(fill no)
			(layer "F.Fab")
		)
		(pad "1" smd rect
			(at 0 -0.9652 90)
			(size 1.397 1.143)
			(layers "F.Cu" "F.Mask" "F.Paste")
			(net "P1V8_PWR")
		)
		(pad "2" smd rect
			(at 0 0.9652 90)
			(size 1.397 1.143)
			(layers "F.Cu" "F.Mask" "F.Paste")
			(net "GND")
		)
	)
	(footprint ""
		(layer "F.Cu")
		(at 59.817 -62.738 -90)
		(property "Reference" "C13"
			(at 0 0 270)
			(layer "F.SilkS")
			(hide yes)
			(effects
				(font
					(size 1.27 1.27)
				)
			)
		)
		(property "Value" "SCD1U16V2KX-3GP"
			(at 1.1811 -2.7051 270)
			(unlocked yes)
			(layer "F.Fab")
			(hide yes)
			(effects
				(font
					(size 1.016 1.016)
					(thickness 0.1524)
				)
			)
		)
		(property "Device Type" "C402H22"
			(at 1.1811 -4.2291 270)
			(unlocked yes)
			(layer "F.Fab")
			(hide yes)
			(effects
				(font
					(size 1.016 1.016)
					(thickness 0.1524)
				)
			)
		)
		(duplicate_pad_numbers_are_jumpers no)
		(fp_rect
			(start -0.4318 0.9525)
			(end 0.4318 -0.9525)
			(stroke
				(width 0)
				(type default)
			)
			(fill no)
			(layer "F.CrtYd")
		)
		(fp_rect
			(start -0.4318 0.9525)
			(end 0.4318 -0.9525)
			(stroke
				(width 0)
				(type default)
			)
			(fill no)
			(layer "F.Fab")
		)
		(pad "1" smd custom
			(at 0 -0.4445 270)
			(size 0.1524 0.1524)
			(layers "F.Cu" "F.Mask" "F.Paste")
			(net "P3V3_PWR")
			(options
				(clearance outline)
				(anchor circle)
			)
			(primitives
				(gr_poly
					(pts
						(arc
							(start 0.3048 -0.2032)
							(mid 0.275042 -0.275042)
							(end 0.2032 -0.3048)
						)
						(arc
							(start -0.2032 -0.3048)
							(mid -0.275042 -0.275042)
							(end -0.3048 -0.2032)
						)
						(arc
							(start -0.3048 0.2032)
							(mid -0.275042 0.275042)
							(end -0.2032 0.3048)
						)
						(arc
							(start 0.2032 0.3048)
							(mid 0.275042 0.275042)
							(end 0.3048 0.2032)
						)
					)
					(width 0)
					(fill yes)
				)
			)
		)
		(pad "2" smd custom
			(at 0 0.4445 270)
			(size 0.1524 0.1524)
			(layers "F.Cu" "F.Mask" "F.Paste")
			(net "GND")
			(options
				(clearance outline)
				(anchor circle)
			)
			(primitives
				(gr_poly
					(pts
						(arc
							(start 0.3048 -0.2032)
							(mid 0.275042 -0.275042)
							(end 0.2032 -0.3048)
						)
						(arc
							(start -0.2032 -0.3048)
							(mid -0.275042 -0.275042)
							(end -0.3048 -0.2032)
						)
						(arc
							(start -0.3048 0.2032)
							(mid -0.275042 0.275042)
							(end -0.2032 0.3048)
						)
						(arc
							(start 0.2032 0.3048)
							(mid 0.275042 0.275042)
							(end 0.3048 0.2032)
						)
					)
					(width 0)
					(fill yes)
				)
			)
		)
	)
	(footprint ""
		(layer "F.Cu")
		(at 26.162 -71.755)
		(property "Reference" "C10"
			(at 0 0 0)
			(layer "F.SilkS")
			(hide yes)
			(effects
				(font
					(size 1.27 1.27)
				)
			)
		)
		(property "Value" "SCD1U16V2KX-3GP"
			(at 1.1811 -2.7051 0)
			(unlocked yes)
			(layer "F.Fab")
			(hide yes)
			(effects
				(font
					(size 1.016 1.016)
					(thickness 0.1524)
				)
			)
		)
		(property "Device Type" "C402H22"
			(at 1.1811 -4.2291 0)
			(unlocked yes)
			(layer "F.Fab")
			(hide yes)
			(effects
				(font
					(size 1.016 1.016)
					(thickness 0.1524)
				)
			)
		)
		(duplicate_pad_numbers_are_jumpers no)
		(fp_rect
			(start -0.4318 0.9525)
			(end 0.4318 -0.9525)
			(stroke
				(width 0)
				(type default)
			)
			(fill no)
			(layer "F.CrtYd")
		)
		(fp_rect
			(start -0.4318 0.9525)
			(end 0.4318 -0.9525)
			(stroke
				(width 0)
				(type default)
			)
			(fill no)
			(layer "F.Fab")
		)
		(pad "1" smd custom
			(at 0 -0.4445)
			(size 0.1524 0.1524)
			(layers "F.Cu" "F.Mask" "F.Paste")
			(net "P3V3_DPB")
			(options
				(clearance outline)
				(anchor circle)
			)
			(primitives
				(gr_poly
					(pts
						(arc
							(start 0.3048 -0.2032)
							(mid 0.275042 -0.275042)
							(end 0.2032 -0.3048)
						)
						(arc
							(start -0.2032 -0.3048)
							(mid -0.275042 -0.275042)
							(end -0.3048 -0.2032)
						)
						(arc
							(start -0.3048 0.2032)
							(mid -0.275042 0.275042)
							(end -0.2032 0.3048)
						)
						(arc
							(start 0.2032 0.3048)
							(mid 0.275042 0.275042)
							(end 0.3048 0.2032)
						)
					)
					(width 0)
					(fill yes)
				)
			)
		)
		(pad "2" smd custom
			(at 0 0.4445)
			(size 0.1524 0.1524)
			(layers "F.Cu" "F.Mask" "F.Paste")
			(net "GND")
			(options
				(clearance outline)
				(anchor circle)
			)
			(primitives
				(gr_poly
					(pts
						(arc
							(start 0.3048 -0.2032)
							(mid 0.275042 -0.275042)
							(end 0.2032 -0.3048)
						)
						(arc
							(start -0.2032 -0.3048)
							(mid -0.275042 -0.275042)
							(end -0.3048 -0.2032)
						)
						(arc
							(start -0.3048 0.2032)
							(mid -0.275042 0.275042)
							(end -0.2032 0.3048)
						)
						(arc
							(start 0.2032 0.3048)
							(mid 0.275042 0.275042)
							(end 0.3048 0.2032)
						)
					)
					(width 0)
					(fill yes)
				)
			)
		)
	)
)
